(kicad_pcb
	(version 20260206)
	(generator "pcbnew")
	(generator_version "10.0")
	(general
		(thickness 1.6)
		(legacy_teardrops no)
	)
	(paper "A4")
	(title_block
		(title "peb — Lightning_PEB_BRD.brd")
		(comment 1 "Lightning (Wiwynn / Facebook NVMe JBOF) / footprints 365-372 of 2563")
	)
	(layers
		(0 "F.Cu" signal "TOP")
		(4 "In1.Cu" signal "L2GND")
		(6 "In2.Cu" signal "L3")
		(8 "In3.Cu" signal "L4VCC")
		(10 "In4.Cu" signal "L5VCC")
		(12 "In5.Cu" signal "L6")
		(14 "In6.Cu" signal "L7GND")
		(2 "B.Cu" signal "BOTTOM")
		(9 "F.Adhes" user "F.Adhesive")
		(11 "B.Adhes" user "B.Adhesive")
		(13 "F.Paste" user "Package Geometry/Pastemask Top")
		(15 "B.Paste" user "Package Geometry/Pastemask Bottom")
		(5 "F.SilkS" user "Ref Des/Silkscreen Top")
		(7 "B.SilkS" user "Ref Des/Silkscreen Bottom")
		(1 "F.Mask" user "Board Geometry/Soldermask Top")
		(3 "B.Mask" user "Board Geometry/Soldermask Bottom")
		(17 "Dwgs.User" user "User.Drawings")
		(19 "Cmts.User" user "User.Comments")
		(21 "Eco1.User" user "User.Eco1")
		(23 "Eco2.User" user "User.Eco2")
		(25 "Edge.Cuts" user "Board Geometry/Outline")
		(27 "Margin" user)
		(31 "F.CrtYd" user "Package Geometry/Place Bound Top")
		(29 "B.CrtYd" user "Package Geometry/Place Bound Bottom")
		(35 "F.Fab" user "Ref Des/Assembly Top")
		(33 "B.Fab" user "Ref Des/Assembly Bottom")
	)
	(footprint ""
		(layer "F.Cu")
		(at 128.391158 -74.60996 180)
		(property "Reference" "C724"
			(at 0 0 180)
			(layer "F.SilkS")
			(hide yes)
			(effects
				(font
					(size 1.27 1.27)
				)
			)
		)
		(property "Value" "SCD1U10V2KX-5GP"
			(at 1.1811 -2.7051 180)
			(unlocked yes)
			(layer "F.Fab")
			(hide yes)
			(effects
				(font
					(size 1.016 1.016)
					(thickness 0.1524)
				)
			)
		)
		(property "Device Type" "C402H22"
			(at 1.1811 -4.2291 180)
			(unlocked yes)
			(layer "F.Fab")
			(hide yes)
			(effects
				(font
					(size 1.016 1.016)
					(thickness 0.1524)
				)
			)
		)
		(duplicate_pad_numbers_are_jumpers no)
		(fp_rect
			(start -0.4318 0.9525)
			(end 0.4318 -0.9525)
			(stroke
				(width 0)
				(type default)
			)
			(fill no)
			(layer "F.CrtYd")
		)
		(fp_rect
			(start -0.4318 0.9525)
			(end 0.4318 -0.9525)
			(stroke
				(width 0)
				(type default)
			)
			(fill no)
			(layer "F.Fab")
		)
		(pad "1" smd custom
			(at 0 -0.4445 180)
			(size 0.1524 0.1524)
			(layers "F.Cu" "F.Mask" "F.Paste")
			(net "P1V8_STBY")
			(options
				(clearance outline)
				(anchor circle)
			)
			(primitives
				(gr_poly
					(pts
						(arc
							(start 0.3048 -0.2032)
							(mid 0.275042 -0.275042)
							(end 0.2032 -0.3048)
						)
						(arc
							(start -0.2032 -0.3048)
							(mid -0.275042 -0.275042)
							(end -0.3048 -0.2032)
						)
						(arc
							(start -0.3048 0.2032)
							(mid -0.275042 0.275042)
							(end -0.2032 0.3048)
						)
						(arc
							(start 0.2032 0.3048)
							(mid 0.275042 0.275042)
							(end 0.3048 0.2032)
						)
					)
					(width 0)
					(fill yes)
				)
			)
		)
		(pad "2" smd custom
			(at 0 0.4445 180)
			(size 0.1524 0.1524)
			(layers "F.Cu" "F.Mask" "F.Paste")
			(net "GND")
			(options
				(clearance outline)
				(anchor circle)
			)
			(primitives
				(gr_poly
					(pts
						(arc
							(start 0.3048 -0.2032)
							(mid 0.275042 -0.275042)
							(end 0.2032 -0.3048)
						)
						(arc
							(start -0.2032 -0.3048)
							(mid -0.275042 -0.275042)
							(end -0.3048 -0.2032)
						)
						(arc
							(start -0.3048 0.2032)
							(mid -0.275042 0.275042)
							(end -0.2032 0.3048)
						)
						(arc
							(start 0.2032 0.3048)
							(mid 0.275042 0.275042)
							(end 0.3048 0.2032)
						)
					)
					(width 0)
					(fill yes)
				)
			)
		)
	)
	(footprint ""
		(layer "F.Cu")
		(at 338.868512 -184.878218 180)
		(property "Reference" "R7946"
			(at 0 0 180)
			(layer "F.SilkS")
			(hide yes)
			(effects
				(font
					(size 1.27 1.27)
				)
			)
		)
		(property "Value" "0R2J-2-GP"
			(at 0.064008 -3.993896 180)
			(unlocked yes)
			(layer "F.Fab")
			(hide yes)
			(effects
				(font
					(size 1.016 1.016)
					(thickness 0.1524)
				)
			)
		)
		(property "Device Type" "R402H16"
			(at 0.064008 -5.517896 180)
			(unlocked yes)
			(layer "F.Fab")
			(hide yes)
			(effects
				(font
					(size 1.016 1.016)
					(thickness 0.1524)
				)
			)
		)
		(duplicate_pad_numbers_are_jumpers no)
		(fp_line
			(start 0.508 -0.9398)
			(end -0.508 -0.9398)
			(stroke
				(width 0.1524)
				(type default)
			)
			(layer "F.SilkS")
		)
		(fp_line
			(start -0.508 -0.9398)
			(end -0.508 0.9398)
			(stroke
				(width 0.1524)
				(type default)
			)
			(layer "F.SilkS")
		)
		(fp_rect
			(start -0.508 0.9398)
			(end 0.508 -0.9398)
			(stroke
				(width 0)
				(type default)
			)
			(fill no)
			(layer "F.CrtYd")
		)
		(fp_rect
			(start -0.508 0.9398)
			(end 0.508 -0.9398)
			(stroke
				(width 0)
				(type default)
			)
			(fill no)
			(layer "F.Fab")
		)
		(pad "1" smd custom
			(at 0 -0.4445 180)
			(size 0.1397 0.1397)
			(layers "F.Cu" "F.Mask" "F.Paste")
			(net "SSD_ATNLED#14")
			(options
				(clearance outline)
				(anchor circle)
			)
			(primitives
				(gr_poly
					(pts
						(arc
							(start -0.1778 -0.2794)
							(mid -0.249642 -0.249642)
							(end -0.2794 -0.1778)
						)
						(arc
							(start -0.2794 0.1778)
							(mid -0.249642 0.249642)
							(end -0.1778 0.2794)
						)
						(arc
							(start 0.1778 0.2794)
							(mid 0.249642 0.249642)
							(end 0.2794 0.1778)
						)
						(arc
							(start 0.2794 -0.1778)
							(mid 0.249642 -0.249642)
							(end 0.1778 -0.2794)
						)
					)
					(width 0)
					(fill yes)
				)
			)
		)
		(pad "2" smd custom
			(at 0 0.4445 180)
			(size 0.1397 0.1397)
			(layers "F.Cu" "F.Mask" "F.Paste")
			(net "SSD_ATNLED#14_R")
			(options
				(clearance outline)
				(anchor circle)
			)
			(primitives
				(gr_poly
					(pts
						(arc
							(start -0.1778 -0.2794)
							(mid -0.249642 -0.249642)
							(end -0.2794 -0.1778)
						)
						(arc
							(start -0.2794 0.1778)
							(mid -0.249642 0.249642)
							(end -0.1778 0.2794)
						)
						(arc
							(start 0.1778 0.2794)
							(mid 0.249642 0.249642)
							(end 0.2794 0.1778)
						)
						(arc
							(start 0.2794 -0.1778)
							(mid 0.249642 -0.249642)
							(end 0.1778 -0.2794)
						)
					)
					(width 0)
					(fill yes)
				)
			)
		)
	)
	(footprint ""
		(layer "F.Cu")
		(at 73.763124 -183.235092)
		(property "Reference" "R7952"
			(at 0 0 0)
			(layer "F.SilkS")
			(hide yes)
			(effects
				(font
					(size 1.27 1.27)
				)
			)
		)
		(property "Value" "0R2J-2-GP"
			(at 0.064008 -3.993896 0)
			(unlocked yes)
			(layer "F.Fab")
			(hide yes)
			(effects
				(font
					(size 1.016 1.016)
					(thickness 0.1524)
				)
			)
		)
		(property "Device Type" "R402H16"
			(at 0.064008 -5.517896 0)
			(unlocked yes)
			(layer "F.Fab")
			(hide yes)
			(effects
				(font
					(size 1.016 1.016)
					(thickness 0.1524)
				)
			)
		)
		(duplicate_pad_numbers_are_jumpers no)
		(fp_line
			(start -0.508 -0.9398)
			(end -0.508 0.9398)
			(stroke
				(width 0.1524)
				(type default)
			)
			(layer "F.SilkS")
		)
		(fp_line
			(start 0.508 -0.9398)
			(end -0.508 -0.9398)
			(stroke
				(width 0.1524)
				(type default)
			)
			(layer "F.SilkS")
		)
		(fp_rect
			(start -0.508 0.9398)
			(end 0.508 -0.9398)
			(stroke
				(width 0)
				(type default)
			)
			(fill no)
			(layer "F.CrtYd")
		)
		(fp_rect
			(start -0.508 0.9398)
			(end 0.508 -0.9398)
			(stroke
				(width 0)
				(type default)
			)
			(fill no)
			(layer "F.Fab")
		)
		(pad "1" smd custom
			(at 0 -0.4445)
			(size 0.1397 0.1397)
			(layers "F.Cu" "F.Mask" "F.Paste")
			(net "SSD_PWREN0")
			(options
				(clearance outline)
				(anchor circle)
			)
			(primitives
				(gr_poly
					(pts
						(arc
							(start -0.1778 -0.2794)
							(mid -0.249642 -0.249642)
							(end -0.2794 -0.1778)
						)
						(arc
							(start -0.2794 0.1778)
							(mid -0.249642 0.249642)
							(end -0.1778 0.2794)
						)
						(arc
							(start 0.1778 0.2794)
							(mid 0.249642 0.249642)
							(end 0.2794 0.1778)
						)
						(arc
							(start 0.2794 -0.1778)
							(mid 0.249642 -0.249642)
							(end 0.1778 -0.2794)
						)
					)
					(width 0)
					(fill yes)
				)
			)
		)
		(pad "2" smd custom
			(at 0 0.4445)
			(size 0.1397 0.1397)
			(layers "F.Cu" "F.Mask" "F.Paste")
			(net "SSD_PWREN0_R")
			(options
				(clearance outline)
				(anchor circle)
			)
			(primitives
				(gr_poly
					(pts
						(arc
							(start -0.1778 -0.2794)
							(mid -0.249642 -0.249642)
							(end -0.2794 -0.1778)
						)
						(arc
							(start -0.2794 0.1778)
							(mid -0.249642 0.249642)
							(end -0.1778 0.2794)
						)
						(arc
							(start 0.1778 0.2794)
							(mid 0.249642 0.249642)
							(end 0.2794 0.1778)
						)
						(arc
							(start 0.2794 -0.1778)
							(mid 0.249642 -0.249642)
							(end 0.1778 -0.2794)
						)
					)
					(width 0)
					(fill yes)
				)
			)
		)
	)
	(footprint ""
		(layer "F.Cu")
		(at 267.462 -5.6388 -90)
		(property "Reference" "R7903"
			(at 0 0 270)
			(layer "F.SilkS")
			(hide yes)
			(effects
				(font
					(size 1.27 1.27)
				)
			)
		)
		(property "Value" "0R2J-2-GP"
			(at 0.064008 -3.993896 270)
			(unlocked yes)
			(layer "F.Fab")
			(hide yes)
			(effects
				(font
					(size 1.016 1.016)
					(thickness 0.1524)
				)
			)
		)
		(property "Device Type" "R402H16"
			(at 0.064008 -5.517896 270)
			(unlocked yes)
			(layer "F.Fab")
			(hide yes)
			(effects
				(font
					(size 1.016 1.016)
					(thickness 0.1524)
				)
			)
		)
		(duplicate_pad_numbers_are_jumpers no)
		(fp_line
			(start -0.508 -0.9398)
			(end -0.508 0.9398)
			(stroke
				(width 0.1524)
				(type default)
			)
			(layer "F.SilkS")
		)
		(fp_line
			(start 0.508 -0.9398)
			(end -0.508 -0.9398)
			(stroke
				(width 0.1524)
				(type default)
			)
			(layer "F.SilkS")
		)
		(fp_rect
			(start -0.508 0.9398)
			(end 0.508 -0.9398)
			(stroke
				(width 0)
				(type default)
			)
			(fill no)
			(layer "F.CrtYd")
		)
		(fp_rect
			(start -0.508 0.9398)
			(end 0.508 -0.9398)
			(stroke
				(width 0)
				(type default)
			)
			(fill no)
			(layer "F.Fab")
		)
		(pad "1" smd custom
			(at 0 -0.4445 270)
			(size 0.1397 0.1397)
			(layers "F.Cu" "F.Mask" "F.Paste")
			(net "ADM6315_PM8536_RST#")
			(options
				(clearance outline)
				(anchor circle)
			)
			(primitives
				(gr_poly
					(pts
						(arc
							(start -0.1778 -0.2794)
							(mid -0.249642 -0.249642)
							(end -0.2794 -0.1778)
						)
						(arc
							(start -0.2794 0.1778)
							(mid -0.249642 0.249642)
							(end -0.1778 0.2794)
						)
						(arc
							(start 0.1778 0.2794)
							(mid 0.249642 0.249642)
							(end 0.2794 0.1778)
						)
						(arc
							(start 0.2794 -0.1778)
							(mid 0.249642 -0.249642)
							(end 0.1778 -0.2794)
						)
					)
					(width 0)
					(fill yes)
				)
			)
		)
		(pad "2" smd custom
			(at 0 0.4445 270)
			(size 0.1397 0.1397)
			(layers "F.Cu" "F.Mask" "F.Paste")
			(net "PM8536_RST#")
			(options
				(clearance outline)
				(anchor circle)
			)
			(primitives
				(gr_poly
					(pts
						(arc
							(start -0.1778 -0.2794)
							(mid -0.249642 -0.249642)
							(end -0.2794 -0.1778)
						)
						(arc
							(start -0.2794 0.1778)
							(mid -0.249642 0.249642)
							(end -0.1778 0.2794)
						)
						(arc
							(start 0.1778 0.2794)
							(mid 0.249642 0.249642)
							(end 0.2794 0.1778)
						)
						(arc
							(start 0.2794 -0.1778)
							(mid 0.249642 -0.249642)
							(end 0.1778 -0.2794)
						)
					)
					(width 0)
					(fill yes)
				)
			)
		)
	)
	(footprint ""
		(layer "F.Cu")
		(at 41.724072 -117.597682)
		(property "Reference" "TP295"
			(at 0 0 0)
			(layer "F.SilkS")
			(hide yes)
			(effects
				(font
					(size 1.27 1.27)
				)
			)
		)
		(property "Value" "TPAD28-2-GP"
			(at -0.0127 -1.6637 0)
			(unlocked yes)
			(layer "F.Fab")
			(hide yes)
			(effects
				(font
					(size 1.016 1.016)
					(thickness 0.1524)
				)
			)
		)
		(property "Device Type" "TPAD28"
			(at -0.0127 -3.1877 0)
			(unlocked yes)
			(layer "F.Fab")
			(hide yes)
			(effects
				(font
					(size 1.016 1.016)
					(thickness 0.1524)
				)
			)
		)
		(duplicate_pad_numbers_are_jumpers no)
		(fp_poly
			(pts
				(arc
					(start 0.3556 0)
					(mid -0.3556 0)
					(end 0.3556 0)
				)
			)
			(stroke
				(width 0)
				(type default)
			)
			(fill no)
			(layer "F.CrtYd")
		)
		(fp_poly
			(pts
				(arc
					(start 0.6096 0)
					(mid -0.6096 0)
					(end 0.6096 0)
				)
			)
			(stroke
				(width 0)
				(type default)
			)
			(fill no)
			(layer "F.Fab")
		)
		(pad "1" smd circle
			(at 0 0)
			(size 0.7112 0.7112)
			(layers "F.Cu" "F.Mask" "F.Paste")
			(net "TP_GPIOV5")
		)
	)
	(footprint ""
		(layer "F.Cu")
		(at 49.911 -192.913 -90)
		(property "Reference" "C703"
			(at 0 0 270)
			(layer "F.SilkS")
			(hide yes)
			(effects
				(font
					(size 1.27 1.27)
				)
			)
		)
		(property "Value" "SC220P50V3JN-GP"
			(at 0 -2.8194 270)
			(unlocked yes)
			(layer "F.Fab")
			(hide yes)
			(effects
				(font
					(size 1.016 1.016)
					(thickness 0.1524)
				)
			)
		)
		(property "Device Type" "C603H36"
			(at 0 -4.3434 270)
			(unlocked yes)
			(layer "F.Fab")
			(hide yes)
			(effects
				(font
					(size 1.016 1.016)
					(thickness 0.1524)
				)
			)
		)
		(duplicate_pad_numbers_are_jumpers no)
		(fp_line
			(start 0.508 0)
			(end -0.508 0)
			(stroke
				(width 0.2032)
				(type default)
			)
			(layer "F.SilkS")
		)
		(fp_rect
			(start -0.5842 1.3335)
			(end 0.5842 -1.3335)
			(stroke
				(width 0)
				(type default)
			)
			(fill no)
			(layer "F.CrtYd")
		)
		(fp_rect
			(start -0.5842 1.3335)
			(end 0.5842 -1.3335)
			(stroke
				(width 0)
				(type default)
			)
			(fill no)
			(layer "F.Fab")
		)
		(pad "1" smd custom
			(at 0 -0.762 270)
			(size 0.2159 0.2159)
			(layers "F.Cu" "F.Mask" "F.Paste")
			(net "BMC_I2C7_B_DPB_SDA_R")
			(options
				(clearance outline)
				(anchor circle)
			)
			(primitives
				(gr_poly
					(pts
						(arc
							(start -0.3302 -0.4318)
							(mid -0.402042 -0.402042)
							(end -0.4318 -0.3302)
						)
						(arc
							(start -0.4318 0.3302)
							(mid -0.402042 0.402042)
							(end -0.3302 0.4318)
						)
						(arc
							(start 0.3302 0.4318)
							(mid 0.402042 0.402042)
							(end 0.4318 0.3302)
						)
						(arc
							(start 0.4318 -0.3302)
							(mid 0.402042 -0.402042)
							(end 0.3302 -0.4318)
						)
					)
					(width 0)
					(fill yes)
				)
			)
		)
		(pad "2" smd custom
			(at 0 0.762 270)
			(size 0.2159 0.2159)
			(layers "F.Cu" "F.Mask" "F.Paste")
			(net "GND")
			(options
				(clearance outline)
				(anchor circle)
			)
			(primitives
				(gr_poly
					(pts
						(arc
							(start -0.3302 -0.4318)
							(mid -0.402042 -0.402042)
							(end -0.4318 -0.3302)
						)
						(arc
							(start -0.4318 0.3302)
							(mid -0.402042 0.402042)
							(end -0.3302 0.4318)
						)
						(arc
							(start 0.3302 0.4318)
							(mid 0.402042 0.402042)
							(end 0.4318 0.3302)
						)
						(arc
							(start 0.4318 -0.3302)
							(mid 0.402042 -0.402042)
							(end 0.3302 -0.4318)
						)
					)
					(width 0)
					(fill yes)
				)
			)
		)
	)
	(footprint ""
		(layer "F.Cu")
		(at 25.4 -150.495 -90)
		(property "Reference" "R297"
			(at 0 0 270)
			(layer "F.SilkS")
			(hide yes)
			(effects
				(font
					(size 1.27 1.27)
				)
			)
		)
		(property "Value" "4K7R2F-GP"
			(at 0.064008 -3.993896 270)
			(unlocked yes)
			(layer "F.Fab")
			(hide yes)
			(effects
				(font
					(size 1.016 1.016)
					(thickness 0.1524)
				)
			)
		)
		(property "Device Type" "R402H16"
			(at 0.064008 -5.517896 270)
			(unlocked yes)
			(layer "F.Fab")
			(hide yes)
			(effects
				(font
					(size 1.016 1.016)
					(thickness 0.1524)
				)
			)
		)
		(duplicate_pad_numbers_are_jumpers no)
		(fp_line
			(start -0.508 -0.9398)
			(end -0.508 0.9398)
			(stroke
				(width 0.1524)
				(type default)
			)
			(layer "F.SilkS")
		)
		(fp_line
			(start 0.508 -0.9398)
			(end -0.508 -0.9398)
			(stroke
				(width 0.1524)
				(type default)
			)
			(layer "F.SilkS")
		)
		(fp_rect
			(start -0.508 0.9398)
			(end 0.508 -0.9398)
			(stroke
				(width 0)
				(type default)
			)
			(fill no)
			(layer "F.CrtYd")
		)
		(fp_rect
			(start -0.508 0.9398)
			(end 0.508 -0.9398)
			(stroke
				(width 0)
				(type default)
			)
			(fill no)
			(layer "F.Fab")
		)
		(pad "1" smd custom
			(at 0 -0.4445 270)
			(size 0.1397 0.1397)
			(layers "F.Cu" "F.Mask" "F.Paste")
			(net "P3V3_STBY")
			(options
				(clearance outline)
				(anchor circle)
			)
			(primitives
				(gr_poly
					(pts
						(arc
							(start -0.1778 -0.2794)
							(mid -0.249642 -0.249642)
							(end -0.2794 -0.1778)
						)
						(arc
							(start -0.2794 0.1778)
							(mid -0.249642 0.249642)
							(end -0.1778 0.2794)
						)
						(arc
							(start 0.1778 0.2794)
							(mid 0.249642 0.249642)
							(end 0.2794 0.1778)
						)
						(arc
							(start 0.2794 -0.1778)
							(mid 0.249642 -0.249642)
							(end 0.1778 -0.2794)
						)
					)
					(width 0)
					(fill yes)
				)
			)
		)
		(pad "2" smd custom
			(at 0 0.4445 270)
			(size 0.1397 0.1397)
			(layers "F.Cu" "F.Mask" "F.Paste")
			(net "OSC2_CONT")
			(options
				(clearance outline)
				(anchor circle)
			)
			(primitives
				(gr_poly
					(pts
						(arc
							(start -0.1778 -0.2794)
							(mid -0.249642 -0.249642)
							(end -0.2794 -0.1778)
						)
						(arc
							(start -0.2794 0.1778)
							(mid -0.249642 0.249642)
							(end -0.1778 0.2794)
						)
						(arc
							(start 0.1778 0.2794)
							(mid 0.249642 0.249642)
							(end 0.2794 0.1778)
						)
						(arc
							(start 0.2794 -0.1778)
							(mid 0.249642 -0.249642)
							(end 0.1778 -0.2794)
						)
					)
					(width 0)
					(fill yes)
				)
			)
		)
	)
	(footprint ""
		(layer "F.Cu")
		(at 141.592046 -212.420454 180)
		(property "Reference" "C342"
			(at 0 0 180)
			(layer "F.SilkS")
			(hide yes)
			(effects
				(font
					(size 1.27 1.27)
				)
			)
		)
		(property "Value" "SCD22U10V2KX-1GP"
			(at 1.1811 -2.7051 180)
			(unlocked yes)
			(layer "F.Fab")
			(hide yes)
			(effects
				(font
					(size 1.016 1.016)
					(thickness 0.1524)
				)
			)
		)
		(property "Device Type" "C402H22"
			(at 1.1811 -4.2291 180)
			(unlocked yes)
			(layer "F.Fab")
			(hide yes)
			(effects
				(font
					(size 1.016 1.016)
					(thickness 0.1524)
				)
			)
		)
		(duplicate_pad_numbers_are_jumpers no)
		(fp_rect
			(start -0.4318 0.9525)
			(end 0.4318 -0.9525)
			(stroke
				(width 0)
				(type default)
			)
			(fill no)
			(layer "F.CrtYd")
		)
		(fp_rect
			(start -0.4318 0.9525)
			(end 0.4318 -0.9525)
			(stroke
				(width 0)
				(type default)
			)
			(fill no)
			(layer "F.Fab")
		)
		(pad "1" smd custom
			(at 0 -0.4445 180)
			(size 0.1524 0.1524)
			(layers "F.Cu" "F.Mask" "F.Paste")
			(net "PCIE_TX_CAP_P58")
			(options
				(clearance outline)
				(anchor circle)
			)
			(primitives
				(gr_poly
					(pts
						(arc
							(start 0.3048 -0.2032)
							(mid 0.275042 -0.275042)
							(end 0.2032 -0.3048)
						)
						(arc
							(start -0.2032 -0.3048)
							(mid -0.275042 -0.275042)
							(end -0.3048 -0.2032)
						)
						(arc
							(start -0.3048 0.2032)
							(mid -0.275042 0.275042)
							(end -0.2032 0.3048)
						)
						(arc
							(start 0.2032 0.3048)
							(mid 0.275042 0.275042)
							(end 0.3048 0.2032)
						)
					)
					(width 0)
					(fill yes)
				)
			)
		)
		(pad "2" smd custom
			(at 0 0.4445 180)
			(size 0.1524 0.1524)
			(layers "F.Cu" "F.Mask" "F.Paste")
			(net "PCIE_TX_P58")
			(options
				(clearance outline)
				(anchor circle)
			)
			(primitives
				(gr_poly
					(pts
						(arc
							(start 0.3048 -0.2032)
							(mid 0.275042 -0.275042)
							(end 0.2032 -0.3048)
						)
						(arc
							(start -0.2032 -0.3048)
							(mid -0.275042 -0.275042)
							(end -0.3048 -0.2032)
						)
						(arc
							(start -0.3048 0.2032)
							(mid -0.275042 0.275042)
							(end -0.2032 0.3048)
						)
						(arc
							(start 0.2032 0.3048)
							(mid 0.275042 0.275042)
							(end 0.3048 0.2032)
						)
					)
					(width 0)
					(fill yes)
				)
			)
		)
	)
)
